# SCM (Grand Teton) — schematic netlist excerpt (pin names and nets, part order shuffled) for the footprints in the layout excerpt that follows; sources: Cadence DE-HDL packaged netlist, KiCad conversion of 12092022_DA0F0TMDCD0_F0T_Management_Board_D_brd_V3_OCP.brd

C62  Q_CAP  1UF 25V 10% X6S  pkg C0402  page 16 : A = P1V2_AUX ; B = GND
R302  Q_RES  33.2 1% CHIP  pkg 0402LF  page 28 : A = SMB_DEBUG_AUX_LVC3_USB_R1_SDA ; B = SMB_DEBUG_AUX_LVC3_USB_SDA

(kicad_pcb
	(version 20260206)
	(generator "pcbnew")
	(generator_version "10.0")
	(general
		(thickness 1.6)
		(legacy_teardrops no)
	)
	(paper "A4")
	(title_block
		(title "12092022_DA0F0TMDCD0_F0T_Management_Board_D_brd_V3_OCP.brd")
		(comment 1 "Grand Teton / footprints 789-790 of 1440")
	)
	(layers
		(0 "F.Cu" signal "TOP")
		(4 "In1.Cu" signal "GND")
		(6 "In2.Cu" signal "IN1")
		(8 "In3.Cu" signal "GND1")
		(10 "In4.Cu" signal "IN2")
		(12 "In5.Cu" signal "VCC")
		(14 "In6.Cu" signal "VCC1")
		(16 "In7.Cu" signal "IN3")
		(18 "In8.Cu" signal "GND2")
		(20 "In9.Cu" signal "IN4")
		(22 "In10.Cu" signal "GND3")
		(2 "B.Cu" signal "BOTTOM")
		(9 "F.Adhes" user "F.Adhesive")
		(11 "B.Adhes" user "B.Adhesive")
		(13 "F.Paste" user "Package Geometry/Pastemask Top")
		(15 "B.Paste" user "Package Geometry/Pastemask Bottom")
		(5 "F.SilkS" user "Ref Des/Silkscreen Top")
		(7 "B.SilkS" user "Ref Des/Silkscreen Bottom")
		(1 "F.Mask" user "Board Geometry/Soldermask Top")
		(3 "B.Mask" user "Board Geometry/Soldermask Bottom")
		(17 "Dwgs.User" user "User.Drawings")
		(19 "Cmts.User" user "User.Comments")
		(21 "Eco1.User" user "User.Eco1")
		(23 "Eco2.User" user "User.Eco2")
		(25 "Edge.Cuts" user "Board Geometry/Outline")
		(27 "Margin" user)
		(31 "F.CrtYd" user "Package Geometry/Place Bound Top")
		(29 "B.CrtYd" user "Package Geometry/Place Bound Bottom")
		(35 "F.Fab" user "Ref Des/Assembly Top")
		(33 "B.Fab" user "Ref Des/Assembly Bottom")
	)
	(footprint ""
		(layer "B.Cu")
		(at 16.764 -72.771 -90)
		(property "Reference" "R302"
			(at 0 0 90)
			(layer "B.SilkS")
			(hide yes)
			(effects
				(font
					(size 1.27 1.27)
				)
				(justify mirror)
			)
		)
		(property "Value" ""
			(at 0 0 90)
			(layer "B.Fab")
			(effects
				(font
					(size 1.27 1.27)
				)
				(justify mirror)
			)
		)
		(duplicate_pad_numbers_are_jumpers no)
		(fp_line
			(start -0.7874 0.4064)
			(end 0.7874 0.4064)
			(stroke
				(width 0.1524)
				(type default)
			)
			(layer "B.SilkS")
		)
		(fp_line
			(start 0.7874 0.4064)
			(end 0.7874 -0.4064)
			(stroke
				(width 0.1524)
				(type default)
			)
			(layer "B.SilkS")
		)
		(fp_line
			(start -0.7874 -0.4064)
			(end -0.7874 0.4064)
			(stroke
				(width 0.1524)
				(type default)
			)
			(layer "B.SilkS")
		)
		(fp_line
			(start 0.7874 -0.4064)
			(end -0.7874 -0.4064)
			(stroke
				(width 0.1524)
				(type default)
			)
			(layer "B.SilkS")
		)
		(fp_line
			(start -0.67945 0.3048)
			(end -0.120396 0.3048)
			(stroke
				(width 0.1)
				(type default)
			)
			(layer "B.Fab")
		)
		(fp_line
			(start -0.120396 0.3048)
			(end -0.120396 0.2794)
			(stroke
				(width 0.1)
				(type default)
			)
			(layer "B.Fab")
		)
		(fp_line
			(start 0.12065 0.3048)
			(end 0.67945 0.3048)
			(stroke
				(width 0.1)
				(type default)
			)
			(layer "B.Fab")
		)
		(fp_line
			(start 0.67945 0.3048)
			(end 0.67945 -0.305054)
			(stroke
				(width 0.1)
				(type default)
			)
			(layer "B.Fab")
		)
		(fp_line
			(start -0.120396 0.2794)
			(end 0.12065 0.2794)
			(stroke
				(width 0.1)
				(type default)
			)
			(layer "B.Fab")
		)
		(fp_line
			(start 0.12065 0.2794)
			(end 0.12065 0.3048)
			(stroke
				(width 0.1)
				(type default)
			)
			(layer "B.Fab")
		)
		(fp_line
			(start -0.12065 -0.2794)
			(end -0.12065 -0.3048)
			(stroke
				(width 0.1)
				(type default)
			)
			(layer "B.Fab")
		)
		(fp_line
			(start 0.12065 -0.2794)
			(end -0.12065 -0.2794)
			(stroke
				(width 0.1)
				(type default)
			)
			(layer "B.Fab")
		)
		(fp_line
			(start -0.67945 -0.3048)
			(end -0.67945 0.3048)
			(stroke
				(width 0.1)
				(type default)
			)
			(layer "B.Fab")
		)
		(fp_line
			(start -0.12065 -0.3048)
			(end -0.67945 -0.3048)
			(stroke
				(width 0.1)
				(type default)
			)
			(layer "B.Fab")
		)
		(fp_line
			(start 0.12065 -0.305054)
			(end 0.12065 -0.2794)
			(stroke
				(width 0.1)
				(type default)
			)
			(layer "B.Fab")
		)
		(fp_line
			(start 0.67945 -0.305054)
			(end 0.12065 -0.305054)
			(stroke
				(width 0.1)
				(type default)
			)
			(layer "B.Fab")
		)
		(pad "1" smd circle
			(at 0.40005 0 90)
			(size 0 0)
			(layers "B.Cu" "B.Mask" "B.Paste")
			(net "SMB_DEBUG_AUX_LVC3_USB_R1_SDA")
		)
		(pad "2" smd circle
			(at -0.40005 0 90)
			(size 0 0)
			(layers "B.Cu" "B.Mask" "B.Paste")
			(net "SMB_DEBUG_AUX_LVC3_USB_SDA")
		)
	)
	(footprint ""
		(layer "B.Cu")
		(at 72.758808 -37.271706 -90)
		(property "Reference" "C62"
			(at 0 0 90)
			(layer "B.SilkS")
			(hide yes)
			(effects
				(font
					(size 1.27 1.27)
				)
				(justify mirror)
			)
		)
		(property "Value" ""
			(at 0 0 90)
			(layer "B.Fab")
			(effects
				(font
					(size 1.27 1.27)
				)
				(justify mirror)
			)
		)
		(duplicate_pad_numbers_are_jumpers no)
		(fp_line
			(start -0.7874 0.4064)
			(end 0.7874 0.4064)
			(stroke
				(width 0.1524)
				(type default)
			)
			(layer "B.SilkS")
		)
		(fp_line
			(start 0.7874 0.4064)
			(end 0.7874 -0.4064)
			(stroke
				(width 0.1524)
				(type default)
			)
			(layer "B.SilkS")
		)
		(fp_line
			(start -0.7874 -0.4064)
			(end -0.7874 0.4064)
			(stroke
				(width 0.1524)
				(type default)
			)
			(layer "B.SilkS")
		)
		(fp_line
			(start 0.7874 -0.4064)
			(end -0.7874 -0.4064)
			(stroke
				(width 0.1524)
				(type default)
			)
			(layer "B.SilkS")
		)
		(fp_line
			(start -0.67945 0.3048)
			(end -0.120396 0.3048)
			(stroke
				(width 0.1)
				(type default)
			)
			(layer "B.Fab")
		)
		(fp_line
			(start -0.120396 0.3048)
			(end -0.120396 0.2794)
			(stroke
				(width 0.1)
				(type default)
			)
			(layer "B.Fab")
		)
		(fp_line
			(start 0.12065 0.3048)
			(end 0.67945 0.3048)
			(stroke
				(width 0.1)
				(type default)
			)
			(layer "B.Fab")
		)
		(fp_line
			(start 0.67945 0.3048)
			(end 0.67945 -0.305054)
			(stroke
				(width 0.1)
				(type default)
			)
			(layer "B.Fab")
		)
		(fp_line
			(start -0.120396 0.2794)
			(end 0.12065 0.2794)
			(stroke
				(width 0.1)
				(type default)
			)
			(layer "B.Fab")
		)
		(fp_line
			(start 0.12065 0.2794)
			(end 0.12065 0.3048)
			(stroke
				(width 0.1)
				(type default)
			)
			(layer "B.Fab")
		)
		(fp_line
			(start -0.12065 -0.2794)
			(end -0.12065 -0.3048)
			(stroke
				(width 0.1)
				(type default)
			)
			(layer "B.Fab")
		)
		(fp_line
			(start 0.12065 -0.2794)
			(end -0.12065 -0.2794)
			(stroke
				(width 0.1)
				(type default)
			)
			(layer "B.Fab")
		)
		(fp_line
			(start -0.67945 -0.3048)
			(end -0.67945 0.3048)
			(stroke
				(width 0.1)
				(type default)
			)
			(layer "B.Fab")
		)
		(fp_line
			(start -0.12065 -0.3048)
			(end -0.67945 -0.3048)
			(stroke
				(width 0.1)
				(type default)
			)
			(layer "B.Fab")
		)
		(fp_line
			(start 0.12065 -0.305054)
			(end 0.12065 -0.2794)
			(stroke
				(width 0.1)
				(type default)
			)
			(layer "B.Fab")
		)
		(fp_line
			(start 0.67945 -0.305054)
			(end 0.12065 -0.305054)
			(stroke
				(width 0.1)
				(type default)
			)
			(layer "B.Fab")
		)
		(pad "1" smd circle
			(at 0.40005 0 90)
			(size 0 0)
			(layers "B.Cu" "B.Mask" "B.Paste")
			(net "P1V2_AUX")
		)
		(pad "2" smd circle
			(at -0.40005 0 90)
			(size 0 0)
			(layers "B.Cu" "B.Mask" "B.Paste")
			(net "GND")
		)
	)
)
